(kicad_pcb
	(version 20260206)
	(generator "pcbnew")
	(generator_version "10.0")
	(general
		(thickness 1.6)
		(legacy_teardrops no)
	)
	(paper "A4")
	(title_block
		(title "01162023_DA0F0TEBIF0_F0T_Expander_BD_F_brd_V02_OCP.brd")
		(comment 1 "Grand Teton / footprint 2305 of 9728 (J3), pads 1-76 of 130")
	)
	(layers
		(0 "F.Cu" signal "TOP")
		(4 "In1.Cu" signal "GND")
		(6 "In2.Cu" signal "VCC")
		(8 "In3.Cu" signal "VCC1")
		(10 "In4.Cu" signal "GND1")
		(12 "In5.Cu" signal "IN1")
		(14 "In6.Cu" signal "GND2")
		(16 "In7.Cu" signal "IN2")
		(18 "In8.Cu" signal "GND3")
		(20 "In9.Cu" signal "IN3")
		(22 "In10.Cu" signal "GND4")
		(24 "In11.Cu" signal "IN4")
		(26 "In12.Cu" signal "GND5")
		(28 "In13.Cu" signal "IN5")
		(30 "In14.Cu" signal "GND6")
		(32 "In15.Cu" signal "IN6")
		(34 "In16.Cu" signal "GND7")
		(2 "B.Cu" signal "BOTTOM")
		(9 "F.Adhes" user "F.Adhesive")
		(11 "B.Adhes" user "B.Adhesive")
		(13 "F.Paste" user "Package Geometry/Pastemask Top")
		(15 "B.Paste" user "Package Geometry/Pastemask Bottom")
		(5 "F.SilkS" user "Ref Des/Silkscreen Top")
		(7 "B.SilkS" user "Ref Des/Silkscreen Bottom")
		(1 "F.Mask" user "Board Geometry/Soldermask Top")
		(3 "B.Mask" user "Board Geometry/Soldermask Bottom")
		(17 "Dwgs.User" user "User.Drawings")
		(19 "Cmts.User" user "User.Comments")
		(21 "Eco1.User" user "User.Eco1")
		(23 "Eco2.User" user "User.Eco2")
		(25 "Edge.Cuts" user "Board Geometry/Outline")
		(27 "Margin" user)
		(31 "F.CrtYd" user "Package Geometry/Place Bound Top")
		(29 "B.CrtYd" user "Package Geometry/Place Bound Bottom")
		(35 "F.Fab" user "Ref Des/Assembly Top")
		(33 "B.Fab" user "Ref Des/Assembly Bottom")
	)
	(footprint ""
		(layer "F.Cu")
		(at 27.910028 -412.090108)
		(property "Reference" "J3"
			(at 26.184352 2.518918 90)
			(unlocked yes)
			(layer "F.SilkS")
			(effects
				(font
					(size 2.032 1.524)
					(thickness 0.1524)
				)
				(justify left)
			)
		)
		(property "Value" ""
			(at 0 0 0)
			(layer "F.Fab")
			(effects
				(font
					(size 1.27 1.27)
				)
			)
		)
		(duplicate_pad_numbers_are_jumpers no)
		(pad "A1" thru_hole rect
			(at 0 0 180)
			(size 0.71628 0.71628)
			(drill 0.30988)
			(layers "*.Cu" "*.Mask")
			(remove_unused_layers no)
			(net "RST_GPU_PERST_2_BUF_R_N")
			(clearance 0.0508)
			(thermal_gap 0.0508)
			(padstack
				(mode front_inner_back)
				(layer "Inner"
					(shape circle)
					(size 0.71628 0.71628)
					(clearance 0.0508)
				)
				(layer "B.Cu"
					(shape rect)
					(size 0.71628 0.71628)
					(clearance 0.0508)
				)
			)
		)
		(pad "A2" thru_hole circle
			(at 2.199894 0.199898 180)
			(size 0.906272 0.906272)
			(drill 0.499872)
			(layers "*.Cu" "*.Mask")
			(remove_unused_layers no)
			(net "GND")
			(clearance 0.0508)
			(thermal_gap 0.0508)
		)
		(pad "A3" thru_hole circle
			(at 4.400042 0 180)
			(size 0.71628 0.71628)
			(drill 0.30988)
			(layers "*.Cu" "*.Mask")
			(remove_unused_layers no)
			(net "GPU_HGX_DETECT_N")
			(clearance 0.0508)
			(thermal_gap 0.0508)
		)
		(pad "A4" thru_hole circle
			(at 6.599936 0.199898 180)
			(size 0.906272 0.906272)
			(drill 0.499872)
			(layers "*.Cu" "*.Mask")
			(remove_unused_layers no)
			(net "GND")
			(clearance 0.0508)
			(thermal_gap 0.0508)
		)
		(pad "A5" thru_hole circle
			(at 8.800084 0 180)
			(size 0.71628 0.71628)
			(drill 0.30988)
			(layers "*.Cu" "*.Mask")
			(remove_unused_layers no)
			(net "RST_GPU_PERST_1_BUF_R_N")
			(clearance 0.0508)
			(thermal_gap 0.0508)
		)
		(pad "A6" thru_hole circle
			(at 10.999978 0.199898 180)
			(size 0.906272 0.906272)
			(drill 0.499872)
			(layers "*.Cu" "*.Mask")
			(remove_unused_layers no)
			(net "GND")
			(clearance 0.0508)
			(thermal_gap 0.0508)
		)
		(pad "A7" thru_hole circle
			(at 13.199872 0 180)
			(size 0.71628 0.71628)
			(drill 0.30988)
			(layers "*.Cu" "*.Mask")
			(remove_unused_layers no)
			(net "PRSNT_GPU_N")
			(clearance 0.0508)
			(thermal_gap 0.0508)
		)
		(pad "A8" thru_hole circle
			(at 15.40002 0.199898 180)
			(size 0.906272 0.906272)
			(drill 0.499872)
			(layers "*.Cu" "*.Mask")
			(remove_unused_layers no)
			(net "GND")
			(clearance 0.0508)
			(thermal_gap 0.0508)
		)
		(pad "A9" thru_hole circle
			(at 17.599914 0 180)
			(size 0.71628 0.71628)
			(drill 0.30988)
			(layers "*.Cu" "*.Mask")
			(remove_unused_layers no)
			(net "RST_GPU_FPGA_PEX_RST_R_N")
			(clearance 0.0508)
			(thermal_gap 0.0508)
		)
		(pad "A10" thru_hole circle
			(at 19.800062 0.199898 180)
			(size 0.906272 0.906272)
			(drill 0.499872)
			(layers "*.Cu" "*.Mask")
			(remove_unused_layers no)
			(net "GND")
			(clearance 0.0508)
			(thermal_gap 0.0508)
		)
		(pad "B1" thru_hole circle
			(at 0 1.299972 180)
			(size 0.906272 0.906272)
			(drill 0.499872)
			(layers "*.Cu" "*.Mask")
			(remove_unused_layers no)
			(net "GND")
			(clearance 0.0508)
			(thermal_gap 0.0508)
		)
		(pad "B3" thru_hole circle
			(at 4.400042 1.299972 180)
			(size 0.906272 0.906272)
			(drill 0.499872)
			(layers "*.Cu" "*.Mask")
			(remove_unused_layers no)
			(net "GND")
			(clearance 0.0508)
			(thermal_gap 0.0508)
		)
		(pad "B5" thru_hole circle
			(at 8.800084 1.299972 180)
			(size 0.906272 0.906272)
			(drill 0.499872)
			(layers "*.Cu" "*.Mask")
			(remove_unused_layers no)
			(net "GND")
			(clearance 0.0508)
			(thermal_gap 0.0508)
		)
		(pad "B7" thru_hole circle
			(at 13.199872 1.299972 180)
			(size 0.906272 0.906272)
			(drill 0.499872)
			(layers "*.Cu" "*.Mask")
			(remove_unused_layers no)
			(net "GND")
			(clearance 0.0508)
			(thermal_gap 0.0508)
		)
		(pad "B9" thru_hole circle
			(at 17.599914 1.299972 180)
			(size 0.906272 0.906272)
			(drill 0.499872)
			(layers "*.Cu" "*.Mask")
			(remove_unused_layers no)
			(net "GND")
			(clearance 0.0508)
			(thermal_gap 0.0508)
		)
		(pad "C9" thru_hole circle
			(at 17.599914 2.599944 180)
			(size 0.71628 0.71628)
			(drill 0.30988)
			(layers "*.Cu" "*.Mask")
			(remove_unused_layers no)
			(net "GPU_THERM_OVERT_N")
			(clearance 0.0508)
			(thermal_gap 0.0508)
		)
		(pad "D2" thru_hole circle
			(at 2.199894 4.100068 180)
			(size 0.906272 0.906272)
			(drill 0.499872)
			(layers "*.Cu" "*.Mask")
			(remove_unused_layers no)
			(net "GND")
			(clearance 0.0508)
			(thermal_gap 0.0508)
		)
		(pad "D4" thru_hole circle
			(at 6.599936 4.100068 180)
			(size 0.906272 0.906272)
			(drill 0.499872)
			(layers "*.Cu" "*.Mask")
			(remove_unused_layers no)
			(net "GND")
			(clearance 0.0508)
			(thermal_gap 0.0508)
		)
		(pad "D6" thru_hole circle
			(at 10.999978 4.100068 180)
			(size 0.906272 0.906272)
			(drill 0.499872)
			(layers "*.Cu" "*.Mask")
			(remove_unused_layers no)
			(net "GND")
			(clearance 0.0508)
			(thermal_gap 0.0508)
		)
		(pad "D8" thru_hole circle
			(at 15.40002 4.100068 180)
			(size 0.906272 0.906272)
			(drill 0.499872)
			(layers "*.Cu" "*.Mask")
			(remove_unused_layers no)
			(net "GND")
			(clearance 0.0508)
			(thermal_gap 0.0508)
		)
		(pad "D9" thru_hole circle
			(at 17.599914 3.899916 180)
			(size 0.71628 0.71628)
			(drill 0.30988)
			(layers "*.Cu" "*.Mask")
			(remove_unused_layers no)
			(net "GPU_PEX_STRAP0_R")
			(clearance 0.0508)
			(thermal_gap 0.0508)
		)
		(pad "D10" thru_hole circle
			(at 19.800062 4.100068 180)
			(size 0.906272 0.906272)
			(drill 0.499872)
			(layers "*.Cu" "*.Mask")
			(remove_unused_layers no)
			(net "GND")
			(clearance 0.0508)
			(thermal_gap 0.0508)
		)
		(pad "E1" thru_hole circle
			(at 0 5.199888 180)
			(size 0.906272 0.906272)
			(drill 0.499872)
			(layers "*.Cu" "*.Mask")
			(remove_unused_layers no)
			(net "GND")
			(clearance 0.0508)
			(thermal_gap 0.0508)
		)
		(pad "E3" thru_hole circle
			(at 4.400042 5.199888 180)
			(size 0.906272 0.906272)
			(drill 0.499872)
			(layers "*.Cu" "*.Mask")
			(remove_unused_layers no)
			(net "GND")
			(clearance 0.0508)
			(thermal_gap 0.0508)
		)
		(pad "E5" thru_hole circle
			(at 8.800084 5.199888 180)
			(size 0.906272 0.906272)
			(drill 0.499872)
			(layers "*.Cu" "*.Mask")
			(remove_unused_layers no)
			(net "GND")
			(clearance 0.0508)
			(thermal_gap 0.0508)
		)
		(pad "E7" thru_hole circle
			(at 13.199872 5.199888 180)
			(size 0.906272 0.906272)
			(drill 0.499872)
			(layers "*.Cu" "*.Mask")
			(remove_unused_layers no)
			(net "GND")
			(clearance 0.0508)
			(thermal_gap 0.0508)
		)
		(pad "E9" thru_hole circle
			(at 17.599914 5.199888 180)
			(size 0.906272 0.906272)
			(drill 0.499872)
			(layers "*.Cu" "*.Mask")
			(remove_unused_layers no)
			(net "GND")
			(clearance 0.0508)
			(thermal_gap 0.0508)
		)
		(pad "F9" thru_hole circle
			(at 17.599914 6.500114 180)
			(size 0.71628 0.71628)
			(drill 0.30988)
			(layers "*.Cu" "*.Mask")
			(remove_unused_layers no)
			(net "GPU_PWR_BRAKE_R_N")
			(clearance 0.0508)
			(thermal_gap 0.0508)
		)
		(pad "G2" thru_hole circle
			(at 2.199894 7.999984 180)
			(size 0.906272 0.906272)
			(drill 0.499872)
			(layers "*.Cu" "*.Mask")
			(remove_unused_layers no)
			(net "GND")
			(clearance 0.0508)
			(thermal_gap 0.0508)
		)
		(pad "G4" thru_hole circle
			(at 6.599936 7.999984 180)
			(size 0.906272 0.906272)
			(drill 0.499872)
			(layers "*.Cu" "*.Mask")
			(remove_unused_layers no)
			(net "GND")
			(clearance 0.0508)
			(thermal_gap 0.0508)
		)
		(pad "G6" thru_hole circle
			(at 10.999978 7.999984 180)
			(size 0.906272 0.906272)
			(drill 0.499872)
			(layers "*.Cu" "*.Mask")
			(remove_unused_layers no)
			(net "GND")
			(clearance 0.0508)
			(thermal_gap 0.0508)
		)
		(pad "G8" thru_hole circle
			(at 15.40002 7.999984 180)
			(size 0.906272 0.906272)
			(drill 0.499872)
			(layers "*.Cu" "*.Mask")
			(remove_unused_layers no)
			(net "GND")
			(clearance 0.0508)
			(thermal_gap 0.0508)
		)
		(pad "G9" thru_hole circle
			(at 17.599914 7.800086 180)
			(size 0.71628 0.71628)
			(drill 0.30988)
			(layers "*.Cu" "*.Mask")
			(remove_unused_layers no)
			(net "GPU_BASE_ID0_R")
			(clearance 0.0508)
			(thermal_gap 0.0508)
		)
		(pad "G10" thru_hole circle
			(at 19.800062 7.999984 180)
			(size 0.906272 0.906272)
			(drill 0.499872)
			(layers "*.Cu" "*.Mask")
			(remove_unused_layers no)
			(net "GND")
			(clearance 0.0508)
			(thermal_gap 0.0508)
		)
		(pad "H1" thru_hole circle
			(at 0 9.100058 180)
			(size 0.906272 0.906272)
			(drill 0.499872)
			(layers "*.Cu" "*.Mask")
			(remove_unused_layers no)
			(net "GND")
			(clearance 0.0508)
			(thermal_gap 0.0508)
		)
		(pad "H3" thru_hole circle
			(at 4.400042 9.100058 180)
			(size 0.906272 0.906272)
			(drill 0.499872)
			(layers "*.Cu" "*.Mask")
			(remove_unused_layers no)
			(net "GND")
			(clearance 0.0508)
			(thermal_gap 0.0508)
		)
		(pad "H5" thru_hole circle
			(at 8.800084 9.100058 180)
			(size 0.906272 0.906272)
			(drill 0.499872)
			(layers "*.Cu" "*.Mask")
			(remove_unused_layers no)
			(net "GND")
			(clearance 0.0508)
			(thermal_gap 0.0508)
		)
		(pad "H7" thru_hole circle
			(at 13.199872 9.100058 180)
			(size 0.906272 0.906272)
			(drill 0.499872)
			(layers "*.Cu" "*.Mask")
			(remove_unused_layers no)
			(net "GND")
			(clearance 0.0508)
			(thermal_gap 0.0508)
		)
		(pad "H9" thru_hole circle
			(at 17.599914 9.100058 180)
			(size 0.906272 0.906272)
			(drill 0.499872)
			(layers "*.Cu" "*.Mask")
			(remove_unused_layers no)
			(net "GND")
			(clearance 0.0508)
			(thermal_gap 0.0508)
		)
		(pad "H10" thru_hole circle
			(at 19.800062 9.299956 180)
			(size 0.71628 0.71628)
			(drill 0.30988)
			(layers "*.Cu" "*.Mask")
			(remove_unused_layers no)
			(net "GPU_BASE_FPGA_READY")
			(clearance 0.0508)
			(thermal_gap 0.0508)
		)
		(pad "I9" thru_hole circle
			(at 17.599914 10.40003 180)
			(size 0.71628 0.71628)
			(drill 0.30988)
			(layers "*.Cu" "*.Mask")
			(remove_unused_layers no)
			(net "CLK_100M_DB2000QL_GPU_REF2_R_DN")
			(clearance 0.0508)
			(thermal_gap 0.0508)
		)
		(pad "I10" thru_hole circle
			(at 19.800062 10.599928 180)
			(size 0.71628 0.71628)
			(drill 0.30988)
			(layers "*.Cu" "*.Mask")
			(remove_unused_layers no)
			(net "GPU_PEX_STRAP1_R")
			(clearance 0.0508)
			(thermal_gap 0.0508)
		)
		(pad "J2" thru_hole circle
			(at 2.199894 11.8999 180)
			(size 0.906272 0.906272)
			(drill 0.499872)
			(layers "*.Cu" "*.Mask")
			(remove_unused_layers no)
			(net "GND")
			(clearance 0.0508)
			(thermal_gap 0.0508)
		)
		(pad "J4" thru_hole circle
			(at 6.599936 11.8999 180)
			(size 0.906272 0.906272)
			(drill 0.499872)
			(layers "*.Cu" "*.Mask")
			(remove_unused_layers no)
			(net "GND")
			(clearance 0.0508)
			(thermal_gap 0.0508)
		)
		(pad "J6" thru_hole circle
			(at 10.999978 11.8999 180)
			(size 0.906272 0.906272)
			(drill 0.499872)
			(layers "*.Cu" "*.Mask")
			(remove_unused_layers no)
			(net "GND")
			(clearance 0.0508)
			(thermal_gap 0.0508)
		)
		(pad "J8" thru_hole circle
			(at 15.40002 11.8999 180)
			(size 0.906272 0.906272)
			(drill 0.499872)
			(layers "*.Cu" "*.Mask")
			(remove_unused_layers no)
			(net "GND")
			(clearance 0.0508)
			(thermal_gap 0.0508)
		)
		(pad "J9" thru_hole circle
			(at 17.599914 11.700002 180)
			(size 0.71628 0.71628)
			(drill 0.30988)
			(layers "*.Cu" "*.Mask")
			(remove_unused_layers no)
			(net "CLK_100M_DB2000QL_GPU_REF2_R_DP")
			(clearance 0.0508)
			(thermal_gap 0.0508)
		)
		(pad "J10" thru_hole circle
			(at 19.800062 11.8999 180)
			(size 0.906272 0.906272)
			(drill 0.499872)
			(layers "*.Cu" "*.Mask")
			(remove_unused_layers no)
			(net "GND")
			(clearance 0.0508)
			(thermal_gap 0.0508)
		)
		(pad "K1" thru_hole circle
			(at 0 12.999974 180)
			(size 0.906272 0.906272)
			(drill 0.499872)
			(layers "*.Cu" "*.Mask")
			(remove_unused_layers no)
			(net "GND")
			(clearance 0.0508)
			(thermal_gap 0.0508)
		)
		(pad "K3" thru_hole circle
			(at 4.400042 12.999974 180)
			(size 0.906272 0.906272)
			(drill 0.499872)
			(layers "*.Cu" "*.Mask")
			(remove_unused_layers no)
			(net "GND")
			(clearance 0.0508)
			(thermal_gap 0.0508)
		)
		(pad "K5" thru_hole circle
			(at 8.800084 12.999974 180)
			(size 0.906272 0.906272)
			(drill 0.499872)
			(layers "*.Cu" "*.Mask")
			(remove_unused_layers no)
			(net "GND")
			(clearance 0.0508)
			(thermal_gap 0.0508)
		)
		(pad "K7" thru_hole circle
			(at 13.199872 12.999974 180)
			(size 0.906272 0.906272)
			(drill 0.499872)
			(layers "*.Cu" "*.Mask")
			(remove_unused_layers no)
			(net "GND")
			(clearance 0.0508)
			(thermal_gap 0.0508)
		)
		(pad "K9" thru_hole circle
			(at 17.599914 12.999974 180)
			(size 0.906272 0.906272)
			(drill 0.499872)
			(layers "*.Cu" "*.Mask")
			(remove_unused_layers no)
			(net "GND")
			(clearance 0.0508)
			(thermal_gap 0.0508)
		)
		(pad "K10" thru_hole circle
			(at 19.800062 13.199872 180)
			(size 0.71628 0.71628)
			(drill 0.30988)
			(layers "*.Cu" "*.Mask")
			(remove_unused_layers no)
			(net "CLK_100M_GPU_FPGA_REF_DN")
			(clearance 0.0508)
			(thermal_gap 0.0508)
		)
		(pad "L9" thru_hole circle
			(at 17.599914 14.299946 180)
			(size 0.71628 0.71628)
			(drill 0.30988)
			(layers "*.Cu" "*.Mask")
			(remove_unused_layers no)
			(net "USB2_GPU_HMC_DN")
			(clearance 0.0508)
			(thermal_gap 0.0508)
		)
		(pad "L10" thru_hole circle
			(at 19.800062 14.500098 180)
			(size 0.71628 0.71628)
			(drill 0.30988)
			(layers "*.Cu" "*.Mask")
			(remove_unused_layers no)
			(net "CLK_100M_GPU_FPGA_REF_DP")
			(clearance 0.0508)
			(thermal_gap 0.0508)
		)
		(pad "M1_2" thru_hole circle
			(at 2.199894 15.80007 180)
			(size 0.906272 0.906272)
			(drill 0.499872)
			(layers "*.Cu" "*.Mask")
			(remove_unused_layers no)
			(net "GND")
			(clearance 0.0508)
			(thermal_gap 0.0508)
		)
		(pad "M1_4" thru_hole circle
			(at 6.599936 15.80007 180)
			(size 0.906272 0.906272)
			(drill 0.499872)
			(layers "*.Cu" "*.Mask")
			(remove_unused_layers no)
			(net "GND")
			(clearance 0.0508)
			(thermal_gap 0.0508)
		)
		(pad "M1_6" thru_hole circle
			(at 10.999978 15.80007 180)
			(size 0.906272 0.906272)
			(drill 0.499872)
			(layers "*.Cu" "*.Mask")
			(remove_unused_layers no)
			(net "GND")
			(clearance 0.0508)
			(thermal_gap 0.0508)
		)
		(pad "M1_8" thru_hole circle
			(at 15.40002 15.80007 180)
			(size 0.906272 0.906272)
			(drill 0.499872)
			(layers "*.Cu" "*.Mask")
			(remove_unused_layers no)
			(net "GND")
			(clearance 0.0508)
			(thermal_gap 0.0508)
		)
		(pad "M1_10" thru_hole circle
			(at 19.800062 15.80007 180)
			(size 0.906272 0.906272)
			(drill 0.499872)
			(layers "*.Cu" "*.Mask")
			(remove_unused_layers no)
			(net "GND")
			(clearance 0.0508)
			(thermal_gap 0.0508)
		)
		(pad "M2_2" thru_hole circle
			(at 2.199894 26.2001 180)
			(size 0.906272 0.906272)
			(drill 0.499872)
			(layers "*.Cu" "*.Mask")
			(remove_unused_layers no)
			(net "GND")
			(clearance 0.0508)
			(thermal_gap 0.0508)
		)
		(pad "M2_4" thru_hole circle
			(at 6.599936 26.2001 180)
			(size 0.906272 0.906272)
			(drill 0.499872)
			(layers "*.Cu" "*.Mask")
			(remove_unused_layers no)
			(net "GND")
			(clearance 0.0508)
			(thermal_gap 0.0508)
		)
		(pad "M2_6" thru_hole circle
			(at 10.999978 26.2001 180)
			(size 0.906272 0.906272)
			(drill 0.499872)
			(layers "*.Cu" "*.Mask")
			(remove_unused_layers no)
			(net "GND")
			(clearance 0.0508)
			(thermal_gap 0.0508)
		)
		(pad "M2_8" thru_hole circle
			(at 15.40002 26.2001 180)
			(size 0.906272 0.906272)
			(drill 0.499872)
			(layers "*.Cu" "*.Mask")
			(remove_unused_layers no)
			(net "GND")
			(clearance 0.0508)
			(thermal_gap 0.0508)
		)
		(pad "M2_10" thru_hole circle
			(at 19.800062 26.2001 180)
			(size 0.906272 0.906272)
			(drill 0.499872)
			(layers "*.Cu" "*.Mask")
			(remove_unused_layers no)
			(net "GND")
			(clearance 0.0508)
			(thermal_gap 0.0508)
		)
		(pad "M9" thru_hole circle
			(at 17.599914 15.599918 180)
			(size 0.71628 0.71628)
			(drill 0.30988)
			(layers "*.Cu" "*.Mask")
			(remove_unused_layers no)
			(net "USB2_GPU_HMC_DP")
			(clearance 0.0508)
			(thermal_gap 0.0508)
		)
		(pad "N1_1" thru_hole circle
			(at 0 16.89989 180)
			(size 0.906272 0.906272)
			(drill 0.499872)
			(layers "*.Cu" "*.Mask")
			(remove_unused_layers no)
			(net "GND")
			(clearance 0.0508)
			(thermal_gap 0.0508)
		)
		(pad "N1_3" thru_hole circle
			(at 4.400042 16.89989 180)
			(size 0.906272 0.906272)
			(drill 0.499872)
			(layers "*.Cu" "*.Mask")
			(remove_unused_layers no)
			(net "GND")
			(clearance 0.0508)
			(thermal_gap 0.0508)
		)
		(pad "N1_5" thru_hole circle
			(at 8.800084 16.89989 180)
			(size 0.906272 0.906272)
			(drill 0.499872)
			(layers "*.Cu" "*.Mask")
			(remove_unused_layers no)
			(net "GND")
			(clearance 0.0508)
			(thermal_gap 0.0508)
		)
		(pad "N1_7" thru_hole circle
			(at 13.199872 16.89989 180)
			(size 0.906272 0.906272)
			(drill 0.499872)
			(layers "*.Cu" "*.Mask")
			(remove_unused_layers no)
			(net "GND")
			(clearance 0.0508)
			(thermal_gap 0.0508)
		)
		(pad "N1_9" thru_hole circle
			(at 17.599914 16.89989 180)
			(size 0.906272 0.906272)
			(drill 0.499872)
			(layers "*.Cu" "*.Mask")
			(remove_unused_layers no)
			(net "GND")
			(clearance 0.0508)
			(thermal_gap 0.0508)
		)
		(pad "N2_1" thru_hole circle
			(at 0 27.29992 180)
			(size 0.906272 0.906272)
			(drill 0.499872)
			(layers "*.Cu" "*.Mask")
			(remove_unused_layers no)
			(net "GND")
			(clearance 0.0508)
			(thermal_gap 0.0508)
		)
		(pad "N2_3" thru_hole circle
			(at 4.400042 27.29992 180)
			(size 0.906272 0.906272)
			(drill 0.499872)
			(layers "*.Cu" "*.Mask")
			(remove_unused_layers no)
			(net "GND")
			(clearance 0.0508)
			(thermal_gap 0.0508)
		)
		(pad "N2_5" thru_hole circle
			(at 8.800084 27.29992 180)
			(size 0.906272 0.906272)
			(drill 0.499872)
			(layers "*.Cu" "*.Mask")
			(remove_unused_layers no)
			(net "GND")
			(clearance 0.0508)
			(thermal_gap 0.0508)
		)
		(pad "N2_7" thru_hole circle
			(at 13.199872 27.29992 180)
			(size 0.906272 0.906272)
			(drill 0.499872)
			(layers "*.Cu" "*.Mask")
			(remove_unused_layers no)
			(net "GND")
			(clearance 0.0508)
			(thermal_gap 0.0508)
		)
	)
)
